(kicad_pcb
	(version 20260206)
	(generator "pcbnew")
	(generator_version "10.0")
	(general
		(thickness 1.6)
		(legacy_teardrops no)
	)
	(paper "A4")
	(title_block
		(title "9052_F0T_PDB_Converter_Brick_F_V03_1208_1600_OCP.brd")
		(comment 1 "Grand Teton / footprints 375-381 of 578")
	)
	(layers
		(0 "F.Cu" signal "TOP")
		(4 "In1.Cu" signal "GND")
		(6 "In2.Cu" signal "IN1")
		(8 "In3.Cu" signal "GND1")
		(10 "In4.Cu" signal "VCC")
		(12 "In5.Cu" signal "VCC1")
		(14 "In6.Cu" signal "GND2")
		(16 "In7.Cu" signal "IN2")
		(18 "In8.Cu" signal "GND3")
		(2 "B.Cu" signal "BOTTOM")
		(9 "F.Adhes" user "F.Adhesive")
		(11 "B.Adhes" user "B.Adhesive")
		(13 "F.Paste" user "Package Geometry/Pastemask Top")
		(15 "B.Paste" user "Package Geometry/Pastemask Bottom")
		(5 "F.SilkS" user "Ref Des/Silkscreen Top")
		(7 "B.SilkS" user "Ref Des/Silkscreen Bottom")
		(1 "F.Mask" user "Board Geometry/Soldermask Top")
		(3 "B.Mask" user "Board Geometry/Soldermask Bottom")
		(17 "Dwgs.User" user "User.Drawings")
		(19 "Cmts.User" user "User.Comments")
		(21 "Eco1.User" user "User.Eco1")
		(23 "Eco2.User" user "User.Eco2")
		(25 "Edge.Cuts" user "Board Geometry/Outline")
		(27 "Margin" user)
		(31 "F.CrtYd" user "Package Geometry/Place Bound Top")
		(29 "B.CrtYd" user "Package Geometry/Place Bound Bottom")
		(35 "F.Fab" user "Ref Des/Assembly Top")
		(33 "B.Fab" user "Ref Des/Assembly Bottom")
	)
	(footprint ""
		(layer "B.Cu")
		(at 172.850302 -76.708 -90)
		(property "Reference" "PR319"
			(at 0 0 90)
			(layer "B.SilkS")
			(hide yes)
			(effects
				(font
					(size 1.27 1.27)
				)
				(justify mirror)
			)
		)
		(property "Value" ""
			(at 0 0 90)
			(layer "B.Fab")
			(effects
				(font
					(size 1.27 1.27)
				)
				(justify mirror)
			)
		)
		(duplicate_pad_numbers_are_jumpers no)
		(fp_line
			(start -0.7874 0.4064)
			(end 0.7874 0.4064)
			(stroke
				(width 0.1524)
				(type default)
			)
			(layer "B.SilkS")
		)
		(fp_line
			(start 0.7874 0.4064)
			(end 0.7874 -0.4064)
			(stroke
				(width 0.1524)
				(type default)
			)
			(layer "B.SilkS")
		)
		(fp_line
			(start -0.7874 -0.4064)
			(end -0.7874 0.4064)
			(stroke
				(width 0.1524)
				(type default)
			)
			(layer "B.SilkS")
		)
		(fp_line
			(start 0.7874 -0.4064)
			(end -0.7874 -0.4064)
			(stroke
				(width 0.1524)
				(type default)
			)
			(layer "B.SilkS")
		)
		(fp_line
			(start -0.67945 0.3048)
			(end -0.120396 0.3048)
			(stroke
				(width 0.1)
				(type default)
			)
			(layer "B.Fab")
		)
		(fp_line
			(start -0.120396 0.3048)
			(end -0.120396 0.2794)
			(stroke
				(width 0.1)
				(type default)
			)
			(layer "B.Fab")
		)
		(fp_line
			(start 0.12065 0.3048)
			(end 0.67945 0.3048)
			(stroke
				(width 0.1)
				(type default)
			)
			(layer "B.Fab")
		)
		(fp_line
			(start 0.67945 0.3048)
			(end 0.67945 -0.305054)
			(stroke
				(width 0.1)
				(type default)
			)
			(layer "B.Fab")
		)
		(fp_line
			(start -0.120396 0.2794)
			(end 0.12065 0.2794)
			(stroke
				(width 0.1)
				(type default)
			)
			(layer "B.Fab")
		)
		(fp_line
			(start 0.12065 0.2794)
			(end 0.12065 0.3048)
			(stroke
				(width 0.1)
				(type default)
			)
			(layer "B.Fab")
		)
		(fp_line
			(start -0.12065 -0.2794)
			(end -0.12065 -0.3048)
			(stroke
				(width 0.1)
				(type default)
			)
			(layer "B.Fab")
		)
		(fp_line
			(start 0.12065 -0.2794)
			(end -0.12065 -0.2794)
			(stroke
				(width 0.1)
				(type default)
			)
			(layer "B.Fab")
		)
		(fp_line
			(start -0.67945 -0.3048)
			(end -0.67945 0.3048)
			(stroke
				(width 0.1)
				(type default)
			)
			(layer "B.Fab")
		)
		(fp_line
			(start -0.12065 -0.3048)
			(end -0.67945 -0.3048)
			(stroke
				(width 0.1)
				(type default)
			)
			(layer "B.Fab")
		)
		(fp_line
			(start 0.12065 -0.305054)
			(end 0.12065 -0.2794)
			(stroke
				(width 0.1)
				(type default)
			)
			(layer "B.Fab")
		)
		(fp_line
			(start 0.67945 -0.305054)
			(end 0.12065 -0.305054)
			(stroke
				(width 0.1)
				(type default)
			)
			(layer "B.Fab")
		)
		(pad "1" smd circle
			(at 0.40005 0 90)
			(size 0 0)
			(layers "B.Cu" "B.Mask" "B.Paste")
			(net "P12V_MB2_SENSE-")
		)
		(pad "2" smd circle
			(at -0.40005 0 90)
			(size 0 0)
			(layers "B.Cu" "B.Mask" "B.Paste")
			(net "GND")
		)
	)
	(footprint ""
		(layer "B.Cu")
		(at 45.687996 -56.774842)
		(property "Reference" "C98"
			(at 0 0 0)
			(layer "B.SilkS")
			(hide yes)
			(effects
				(font
					(size 1.27 1.27)
				)
				(justify mirror)
			)
		)
		(property "Value" ""
			(at 0 0 0)
			(layer "B.Fab")
			(effects
				(font
					(size 1.27 1.27)
				)
				(justify mirror)
			)
		)
		(duplicate_pad_numbers_are_jumpers no)
		(fp_line
			(start -0.7874 -0.4064)
			(end -0.7874 0.4064)
			(stroke
				(width 0.1524)
				(type default)
			)
			(layer "B.SilkS")
		)
		(fp_line
			(start -0.7874 0.4064)
			(end 0.7874 0.4064)
			(stroke
				(width 0.1524)
				(type default)
			)
			(layer "B.SilkS")
		)
		(fp_line
			(start 0.7874 -0.4064)
			(end -0.7874 -0.4064)
			(stroke
				(width 0.1524)
				(type default)
			)
			(layer "B.SilkS")
		)
		(fp_line
			(start 0.7874 0.4064)
			(end 0.7874 -0.4064)
			(stroke
				(width 0.1524)
				(type default)
			)
			(layer "B.SilkS")
		)
		(fp_line
			(start -0.67945 -0.3048)
			(end -0.67945 0.3048)
			(stroke
				(width 0.1)
				(type default)
			)
			(layer "B.Fab")
		)
		(fp_line
			(start -0.67945 0.3048)
			(end -0.120396 0.3048)
			(stroke
				(width 0.1)
				(type default)
			)
			(layer "B.Fab")
		)
		(fp_line
			(start -0.12065 -0.3048)
			(end -0.67945 -0.3048)
			(stroke
				(width 0.1)
				(type default)
			)
			(layer "B.Fab")
		)
		(fp_line
			(start -0.12065 -0.2794)
			(end -0.12065 -0.3048)
			(stroke
				(width 0.1)
				(type default)
			)
			(layer "B.Fab")
		)
		(fp_line
			(start -0.120396 0.2794)
			(end 0.12065 0.2794)
			(stroke
				(width 0.1)
				(type default)
			)
			(layer "B.Fab")
		)
		(fp_line
			(start -0.120396 0.3048)
			(end -0.120396 0.2794)
			(stroke
				(width 0.1)
				(type default)
			)
			(layer "B.Fab")
		)
		(fp_line
			(start 0.12065 -0.305054)
			(end 0.12065 -0.2794)
			(stroke
				(width 0.1)
				(type default)
			)
			(layer "B.Fab")
		)
		(fp_line
			(start 0.12065 -0.2794)
			(end -0.12065 -0.2794)
			(stroke
				(width 0.1)
				(type default)
			)
			(layer "B.Fab")
		)
		(fp_line
			(start 0.12065 0.2794)
			(end 0.12065 0.3048)
			(stroke
				(width 0.1)
				(type default)
			)
			(layer "B.Fab")
		)
		(fp_line
			(start 0.12065 0.3048)
			(end 0.67945 0.3048)
			(stroke
				(width 0.1)
				(type default)
			)
			(layer "B.Fab")
		)
		(fp_line
			(start 0.67945 -0.305054)
			(end 0.12065 -0.305054)
			(stroke
				(width 0.1)
				(type default)
			)
			(layer "B.Fab")
		)
		(fp_line
			(start 0.67945 0.3048)
			(end 0.67945 -0.305054)
			(stroke
				(width 0.1)
				(type default)
			)
			(layer "B.Fab")
		)
		(pad "1" smd circle
			(at 0.40005 0 180)
			(size 0 0)
			(layers "B.Cu" "B.Mask" "B.Paste")
			(net "P12V_HPDB_0_ISET_R")
		)
		(pad "2" smd circle
			(at -0.40005 0 180)
			(size 0 0)
			(layers "B.Cu" "B.Mask" "B.Paste")
			(net "GND")
		)
	)
	(footprint ""
		(layer "B.Cu")
		(at 212.344 -69.723 -90)
		(property "Reference" "R91"
			(at 0 0 90)
			(layer "B.SilkS")
			(hide yes)
			(effects
				(font
					(size 1.27 1.27)
				)
				(justify mirror)
			)
		)
		(property "Value" ""
			(at 0 0 90)
			(layer "B.Fab")
			(effects
				(font
					(size 1.27 1.27)
				)
				(justify mirror)
			)
		)
		(duplicate_pad_numbers_are_jumpers no)
		(fp_line
			(start -0.7874 0.4064)
			(end 0.7874 0.4064)
			(stroke
				(width 0.1524)
				(type default)
			)
			(layer "B.SilkS")
		)
		(fp_line
			(start 0.7874 0.4064)
			(end 0.7874 -0.4064)
			(stroke
				(width 0.1524)
				(type default)
			)
			(layer "B.SilkS")
		)
		(fp_line
			(start -0.7874 -0.4064)
			(end -0.7874 0.4064)
			(stroke
				(width 0.1524)
				(type default)
			)
			(layer "B.SilkS")
		)
		(fp_line
			(start 0.7874 -0.4064)
			(end -0.7874 -0.4064)
			(stroke
				(width 0.1524)
				(type default)
			)
			(layer "B.SilkS")
		)
		(fp_line
			(start -0.67945 0.3048)
			(end -0.120396 0.3048)
			(stroke
				(width 0.1)
				(type default)
			)
			(layer "B.Fab")
		)
		(fp_line
			(start -0.120396 0.3048)
			(end -0.120396 0.2794)
			(stroke
				(width 0.1)
				(type default)
			)
			(layer "B.Fab")
		)
		(fp_line
			(start 0.12065 0.3048)
			(end 0.67945 0.3048)
			(stroke
				(width 0.1)
				(type default)
			)
			(layer "B.Fab")
		)
		(fp_line
			(start 0.67945 0.3048)
			(end 0.67945 -0.305054)
			(stroke
				(width 0.1)
				(type default)
			)
			(layer "B.Fab")
		)
		(fp_line
			(start -0.120396 0.2794)
			(end 0.12065 0.2794)
			(stroke
				(width 0.1)
				(type default)
			)
			(layer "B.Fab")
		)
		(fp_line
			(start 0.12065 0.2794)
			(end 0.12065 0.3048)
			(stroke
				(width 0.1)
				(type default)
			)
			(layer "B.Fab")
		)
		(fp_line
			(start -0.12065 -0.2794)
			(end -0.12065 -0.3048)
			(stroke
				(width 0.1)
				(type default)
			)
			(layer "B.Fab")
		)
		(fp_line
			(start 0.12065 -0.2794)
			(end -0.12065 -0.2794)
			(stroke
				(width 0.1)
				(type default)
			)
			(layer "B.Fab")
		)
		(fp_line
			(start -0.67945 -0.3048)
			(end -0.67945 0.3048)
			(stroke
				(width 0.1)
				(type default)
			)
			(layer "B.Fab")
		)
		(fp_line
			(start -0.12065 -0.3048)
			(end -0.67945 -0.3048)
			(stroke
				(width 0.1)
				(type default)
			)
			(layer "B.Fab")
		)
		(fp_line
			(start 0.12065 -0.305054)
			(end 0.12065 -0.2794)
			(stroke
				(width 0.1)
				(type default)
			)
			(layer "B.Fab")
		)
		(fp_line
			(start 0.67945 -0.305054)
			(end 0.12065 -0.305054)
			(stroke
				(width 0.1)
				(type default)
			)
			(layer "B.Fab")
		)
		(pad "1" smd circle
			(at 0.40005 0 90)
			(size 0 0)
			(layers "B.Cu" "B.Mask" "B.Paste")
			(net "P3V3_AUX")
		)
		(pad "2" smd circle
			(at -0.40005 0 90)
			(size 0 0)
			(layers "B.Cu" "B.Mask" "B.Paste")
			(net "SKU_ID_1")
		)
	)
	(footprint ""
		(layer "B.Cu")
		(at 238.682784 -88.36279)
		(property "Reference" "R6"
			(at 0 0 0)
			(layer "B.SilkS")
			(hide yes)
			(effects
				(font
					(size 1.27 1.27)
				)
				(justify mirror)
			)
		)
		(property "Value" ""
			(at 0 0 0)
			(layer "B.Fab")
			(effects
				(font
					(size 1.27 1.27)
				)
				(justify mirror)
			)
		)
		(duplicate_pad_numbers_are_jumpers no)
		(fp_line
			(start -0.7874 -0.4064)
			(end -0.7874 0.4064)
			(stroke
				(width 0.1524)
				(type default)
			)
			(layer "B.SilkS")
		)
		(fp_line
			(start -0.7874 0.4064)
			(end 0.7874 0.4064)
			(stroke
				(width 0.1524)
				(type default)
			)
			(layer "B.SilkS")
		)
		(fp_line
			(start 0.7874 -0.4064)
			(end -0.7874 -0.4064)
			(stroke
				(width 0.1524)
				(type default)
			)
			(layer "B.SilkS")
		)
		(fp_line
			(start 0.7874 0.4064)
			(end 0.7874 -0.4064)
			(stroke
				(width 0.1524)
				(type default)
			)
			(layer "B.SilkS")
		)
		(fp_line
			(start -0.67945 -0.3048)
			(end -0.67945 0.3048)
			(stroke
				(width 0.1)
				(type default)
			)
			(layer "B.Fab")
		)
		(fp_line
			(start -0.67945 0.3048)
			(end -0.120396 0.3048)
			(stroke
				(width 0.1)
				(type default)
			)
			(layer "B.Fab")
		)
		(fp_line
			(start -0.12065 -0.3048)
			(end -0.67945 -0.3048)
			(stroke
				(width 0.1)
				(type default)
			)
			(layer "B.Fab")
		)
		(fp_line
			(start -0.12065 -0.2794)
			(end -0.12065 -0.3048)
			(stroke
				(width 0.1)
				(type default)
			)
			(layer "B.Fab")
		)
		(fp_line
			(start -0.120396 0.2794)
			(end 0.12065 0.2794)
			(stroke
				(width 0.1)
				(type default)
			)
			(layer "B.Fab")
		)
		(fp_line
			(start -0.120396 0.3048)
			(end -0.120396 0.2794)
			(stroke
				(width 0.1)
				(type default)
			)
			(layer "B.Fab")
		)
		(fp_line
			(start 0.12065 -0.305054)
			(end 0.12065 -0.2794)
			(stroke
				(width 0.1)
				(type default)
			)
			(layer "B.Fab")
		)
		(fp_line
			(start 0.12065 -0.2794)
			(end -0.12065 -0.2794)
			(stroke
				(width 0.1)
				(type default)
			)
			(layer "B.Fab")
		)
		(fp_line
			(start 0.12065 0.2794)
			(end 0.12065 0.3048)
			(stroke
				(width 0.1)
				(type default)
			)
			(layer "B.Fab")
		)
		(fp_line
			(start 0.12065 0.3048)
			(end 0.67945 0.3048)
			(stroke
				(width 0.1)
				(type default)
			)
			(layer "B.Fab")
		)
		(fp_line
			(start 0.67945 -0.305054)
			(end 0.12065 -0.305054)
			(stroke
				(width 0.1)
				(type default)
			)
			(layer "B.Fab")
		)
		(fp_line
			(start 0.67945 0.3048)
			(end 0.67945 -0.305054)
			(stroke
				(width 0.1)
				(type default)
			)
			(layer "B.Fab")
		)
		(pad "1" smd circle
			(at 0.40005 0 180)
			(size 0 0)
			(layers "B.Cu" "B.Mask" "B.Paste")
			(net "SMB_MB_PDB_SCL")
		)
		(pad "2" smd circle
			(at -0.40005 0 180)
			(size 0 0)
			(layers "B.Cu" "B.Mask" "B.Paste")
			(net "SMB_PDB_MISC_SCL_R")
		)
	)
	(footprint ""
		(layer "B.Cu")
		(at 102.824534 -76.708 -90)
		(property "Reference" "PR65"
			(at 0 0 90)
			(layer "B.SilkS")
			(hide yes)
			(effects
				(font
					(size 1.27 1.27)
				)
				(justify mirror)
			)
		)
		(property "Value" ""
			(at 0 0 90)
			(layer "B.Fab")
			(effects
				(font
					(size 1.27 1.27)
				)
				(justify mirror)
			)
		)
		(duplicate_pad_numbers_are_jumpers no)
		(fp_line
			(start -0.7874 0.4064)
			(end 0.7874 0.4064)
			(stroke
				(width 0.1524)
				(type default)
			)
			(layer "B.SilkS")
		)
		(fp_line
			(start 0.7874 0.4064)
			(end 0.7874 -0.4064)
			(stroke
				(width 0.1524)
				(type default)
			)
			(layer "B.SilkS")
		)
		(fp_line
			(start -0.7874 -0.4064)
			(end -0.7874 0.4064)
			(stroke
				(width 0.1524)
				(type default)
			)
			(layer "B.SilkS")
		)
		(fp_line
			(start 0.7874 -0.4064)
			(end -0.7874 -0.4064)
			(stroke
				(width 0.1524)
				(type default)
			)
			(layer "B.SilkS")
		)
		(fp_line
			(start -0.67945 0.3048)
			(end -0.120396 0.3048)
			(stroke
				(width 0.1)
				(type default)
			)
			(layer "B.Fab")
		)
		(fp_line
			(start -0.120396 0.3048)
			(end -0.120396 0.2794)
			(stroke
				(width 0.1)
				(type default)
			)
			(layer "B.Fab")
		)
		(fp_line
			(start 0.12065 0.3048)
			(end 0.67945 0.3048)
			(stroke
				(width 0.1)
				(type default)
			)
			(layer "B.Fab")
		)
		(fp_line
			(start 0.67945 0.3048)
			(end 0.67945 -0.305054)
			(stroke
				(width 0.1)
				(type default)
			)
			(layer "B.Fab")
		)
		(fp_line
			(start -0.120396 0.2794)
			(end 0.12065 0.2794)
			(stroke
				(width 0.1)
				(type default)
			)
			(layer "B.Fab")
		)
		(fp_line
			(start 0.12065 0.2794)
			(end 0.12065 0.3048)
			(stroke
				(width 0.1)
				(type default)
			)
			(layer "B.Fab")
		)
		(fp_line
			(start -0.12065 -0.2794)
			(end -0.12065 -0.3048)
			(stroke
				(width 0.1)
				(type default)
			)
			(layer "B.Fab")
		)
		(fp_line
			(start 0.12065 -0.2794)
			(end -0.12065 -0.2794)
			(stroke
				(width 0.1)
				(type default)
			)
			(layer "B.Fab")
		)
		(fp_line
			(start -0.67945 -0.3048)
			(end -0.67945 0.3048)
			(stroke
				(width 0.1)
				(type default)
			)
			(layer "B.Fab")
		)
		(fp_line
			(start -0.12065 -0.3048)
			(end -0.67945 -0.3048)
			(stroke
				(width 0.1)
				(type default)
			)
			(layer "B.Fab")
		)
		(fp_line
			(start 0.12065 -0.305054)
			(end 0.12065 -0.2794)
			(stroke
				(width 0.1)
				(type default)
			)
			(layer "B.Fab")
		)
		(fp_line
			(start 0.67945 -0.305054)
			(end 0.12065 -0.305054)
			(stroke
				(width 0.1)
				(type default)
			)
			(layer "B.Fab")
		)
		(pad "1" smd rect
			(at 0.40005 0 270)
			(size 0.4572 0.508)
			(layers "B.Cu" "B.Mask" "B.Paste")
			(net "P12V_MB1_SENSE+")
		)
		(pad "2" smd rect
			(at -0.40005 0 270)
			(size 0.4572 0.508)
			(layers "B.Cu" "B.Mask" "B.Paste")
			(net "P12V_BRICK")
		)
	)
	(footprint ""
		(layer "B.Cu")
		(at 227.203 -95.504 90)
		(property "Reference" "C24"
			(at 0 0 90)
			(layer "B.SilkS")
			(hide yes)
			(effects
				(font
					(size 1.27 1.27)
				)
				(justify mirror)
			)
		)
		(property "Value" ""
			(at 0 0 90)
			(layer "B.Fab")
			(effects
				(font
					(size 1.27 1.27)
				)
				(justify mirror)
			)
		)
		(duplicate_pad_numbers_are_jumpers no)
		(fp_line
			(start 2.2098 -0.9398)
			(end -2.2098 -0.9398)
			(stroke
				(width 0.1524)
				(type default)
			)
			(layer "B.SilkS")
		)
		(fp_line
			(start -2.2098 -0.9398)
			(end -2.2098 0.9398)
			(stroke
				(width 0.1524)
				(type default)
			)
			(layer "B.SilkS")
		)
		(fp_line
			(start 2.2098 0.9398)
			(end 2.2098 -0.9398)
			(stroke
				(width 0.1524)
				(type default)
			)
			(layer "B.SilkS")
		)
		(fp_line
			(start -2.2098 0.9398)
			(end 2.2098 0.9398)
			(stroke
				(width 0.1524)
				(type default)
			)
			(layer "B.SilkS")
		)
		(fp_line
			(start 1.700022 -0.899922)
			(end -1.700022 -0.899922)
			(stroke
				(width 0.1)
				(type default)
			)
			(layer "B.Fab")
		)
		(fp_line
			(start -1.700022 -0.899922)
			(end -1.700022 0.899922)
			(stroke
				(width 0.1)
				(type default)
			)
			(layer "B.Fab")
		)
		(fp_line
			(start 1.700022 0.899922)
			(end 1.700022 -0.899922)
			(stroke
				(width 0.1)
				(type default)
			)
			(layer "B.Fab")
		)
		(fp_line
			(start -1.700022 0.899922)
			(end 1.700022 0.899922)
			(stroke
				(width 0.1)
				(type default)
			)
			(layer "B.Fab")
		)
		(pad "1" smd rect
			(at 1.4732 0 90)
			(size 1.1684 1.5748)
			(layers "B.Cu" "B.Mask" "B.Paste")
			(net "P52V_HS")
		)
		(pad "2" smd rect
			(at -1.4732 0 90)
			(size 1.1684 1.5748)
			(layers "B.Cu" "B.Mask" "B.Paste")
			(net "GND")
		)
	)
	(footprint ""
		(layer "B.Cu")
		(at 215.138 -95.504 90)
		(property "Reference" "C44"
			(at 0 0 90)
			(layer "B.SilkS")
			(hide yes)
			(effects
				(font
					(size 1.27 1.27)
				)
				(justify mirror)
			)
		)
		(property "Value" ""
			(at 0 0 90)
			(layer "B.Fab")
			(effects
				(font
					(size 1.27 1.27)
				)
				(justify mirror)
			)
		)
		(duplicate_pad_numbers_are_jumpers no)
		(fp_line
			(start 2.2098 -0.9398)
			(end -2.2098 -0.9398)
			(stroke
				(width 0.1524)
				(type default)
			)
			(layer "B.SilkS")
		)
		(fp_line
			(start -2.2098 -0.9398)
			(end -2.2098 0.9398)
			(stroke
				(width 0.1524)
				(type default)
			)
			(layer "B.SilkS")
		)
		(fp_line
			(start 2.2098 0.9398)
			(end 2.2098 -0.9398)
			(stroke
				(width 0.1524)
				(type default)
			)
			(layer "B.SilkS")
		)
		(fp_line
			(start -2.2098 0.9398)
			(end 2.2098 0.9398)
			(stroke
				(width 0.1524)
				(type default)
			)
			(layer "B.SilkS")
		)
		(fp_line
			(start 1.700022 -0.899922)
			(end -1.700022 -0.899922)
			(stroke
				(width 0.1)
				(type default)
			)
			(layer "B.Fab")
		)
		(fp_line
			(start -1.700022 -0.899922)
			(end -1.700022 0.899922)
			(stroke
				(width 0.1)
				(type default)
			)
			(layer "B.Fab")
		)
		(fp_line
			(start 1.700022 0.899922)
			(end 1.700022 -0.899922)
			(stroke
				(width 0.1)
				(type default)
			)
			(layer "B.Fab")
		)
		(fp_line
			(start -1.700022 0.899922)
			(end 1.700022 0.899922)
			(stroke
				(width 0.1)
				(type default)
			)
			(layer "B.Fab")
		)
		(pad "1" smd rect
			(at 1.4732 0 90)
			(size 1.1684 1.5748)
			(layers "B.Cu" "B.Mask" "B.Paste")
			(net "P52V_HS")
		)
		(pad "2" smd rect
			(at -1.4732 0 90)
			(size 1.1684 1.5748)
			(layers "B.Cu" "B.Mask" "B.Paste")
			(net "GND")
		)
	)
)
